#ISCELL
  logical_power cad_note *
  *
#ISCELL
  pure_quanta quanta_title_block_c *
  *
#ISCELL
  logical_power universal_gnd *
  page113_i1
#ISCELL
  standard offpage *
  page113_i10
#ISCELL
  standard tap *
  page113_i100
#ISCELL
  standard tap *
  page113_i101
#ISCELL
  standard tap *
  page113_i102
#ISCELL
  standard tap *
  page113_i103
#ISCELL
  standard tap *
  page113_i104
#ISCELL
  standard tap *
  page113_i105
#ISCELL
  standard tap *
  page113_i106
#ISCELL
  standard tap *
  page113_i107
#ISCELL
  standard tap *
  page113_i108
#ISCELL
  standard offpage *
  page113_i109
#ISCELL
  standard offpage *
  page113_i11
#ISCELL
  standard tap *
  page113_i110
#ISCELL
  standard tap *
  page113_i111
#ISCELL
  standard tap *
  page113_i112
#ISCELL
  standard tap *
  page113_i113
#ISCELL
  logical_power universal_gnd *
  page113_i114
#ISCELL
  logical_power universal_gnd *
  page113_i115
#CELL
  pure_quanta q_cap *
  page113_i116
#ISCELL
  logical_power vcc_core *
  page113_i117
#ISCELL
  standard offpage *
  page113_i119
#ISCELL
  logical_power vcc_core *
  page113_i12
#CELL
  pure_quanta q_cap *
  page113_i120
#ISCELL
  logical_power vcc_core *
  page113_i121
#CELL
  pure_quanta q_cap *
  page113_i122
#ISCELL
  logical_power universal_gnd *
  page113_i123
#ISCELL
  standard tap *
  page113_i124
#ISCELL
  standard tap *
  page113_i125
#ISCELL
  standard tap *
  page113_i126
#ISCELL
  standard tap *
  page113_i127
#ISCELL
  standard tap *
  page113_i128
#ISCELL
  standard tap *
  page113_i129
#ISCELL
  standard tap *
  page113_i13
#ISCELL
  standard tap *
  page113_i130
#ISCELL
  standard tap *
  page113_i131
#ISCELL
  standard tap *
  page113_i132
#ISCELL
  standard tap *
  page113_i133
#ISCELL
  standard tap *
  page113_i134
#ISCELL
  standard tap *
  page113_i135
#ISCELL
  standard tap *
  page113_i136
#ISCELL
  standard tap *
  page113_i137
#ISCELL
  standard tap *
  page113_i138
#ISCELL
  standard tap *
  page113_i139
#ISCELL
  standard offpage *
  page113_i14
#ISCELL
  standard tap *
  page113_i140
#ISCELL
  standard tap *
  page113_i141
#ISCELL
  standard tap *
  page113_i142
#ISCELL
  standard tap *
  page113_i143
#ISCELL
  standard tap *
  page113_i144
#ISCELL
  standard tap *
  page113_i145
#ISCELL
  standard tap *
  page113_i146
#ISCELL
  standard tap *
  page113_i147
#ISCELL
  standard tap *
  page113_i148
#ISCELL
  standard tap *
  page113_i149
#ISCELL
  standard offpage *
  page113_i15
#ISCELL
  standard tap *
  page113_i150
#ISCELL
  standard tap *
  page113_i151
#ISCELL
  standard tap *
  page113_i152
#ISCELL
  standard tap *
  page113_i153
#ISCELL
  standard tap *
  page113_i154
#ISCELL
  standard tap *
  page113_i155
#ISCELL
  standard tap *
  page113_i156
#ISCELL
  standard tap *
  page113_i157
#ISCELL
  standard tap *
  page113_i158
#ISCELL
  standard tap *
  page113_i159
#ISCELL
  standard offpage *
  page113_i16
#ISCELL
  standard tap *
  page113_i160
#ISCELL
  standard tap *
  page113_i161
#ISCELL
  standard offpage *
  page113_i162
#ISCELL
  standard offpage *
  page113_i163
#ISCELL
  standard offpage *
  page113_i164
#ISCELL
  standard tap *
  page113_i165
#ISCELL
  standard tap *
  page113_i166
#ISCELL
  standard offpage *
  page113_i167
#ISCELL
  standard offpage *
  page113_i168
#ISCELL
  logical_power vcc_core *
  page113_i169
#ISCELL
  standard offpage *
  page113_i17
#ISCELL
  logical_power universal_gnd *
  page113_i171
#ISCELL
  standard offpage *
  page113_i172
#ISCELL
  standard offpage *
  page113_i173
#ISCELL
  standard offpage *
  page113_i174
#ISCELL
  standard tap *
  page113_i175
#ISCELL
  standard tap *
  page113_i176
#CELL
  pure_quanta sconn288_adr50017p087cc *
  page113_i177
#CELL
  pure_quanta sconn288_adr50017p087cc *
  page113_i179
#ISCELL
  standard offpage *
  page113_i18
#CELL
  pure_quanta sconn288_adr50017p087cc *
  page113_i180
#ISCELL
  standard offpage *
  page113_i181
#CELL
  pure_quanta q_res *
  page113_i182
#ISCELL
  standard offpage *
  page113_i19
#CELL
  pure_quanta q_res *
  page113_i2
#ISCELL
  standard offpage *
  page113_i20
#ISCELL
  standard offpage *
  page113_i21
#ISCELL
  standard tap *
  page113_i22
#ISCELL
  standard tap *
  page113_i23
#ISCELL
  standard tap *
  page113_i24
#ISCELL
  standard tap *
  page113_i25
#ISCELL
  standard tap *
  page113_i26
#ISCELL
  standard tap *
  page113_i27
#ISCELL
  standard tap *
  page113_i28
#ISCELL
  standard tap *
  page113_i29
#ISCELL
  standard offpage *
  page113_i3
#ISCELL
  standard tap *
  page113_i30
#ISCELL
  standard tap *
  page113_i31
#ISCELL
  standard tap *
  page113_i32
#ISCELL
  standard tap *
  page113_i33
#ISCELL
  standard tap *
  page113_i34
#ISCELL
  standard tap *
  page113_i35
#ISCELL
  standard tap *
  page113_i36
#ISCELL
  standard tap *
  page113_i37
#ISCELL
  standard tap *
  page113_i38
#ISCELL
  standard tap *
  page113_i39
#ISCELL
  standard tap *
  page113_i40
#ISCELL
  standard tap *
  page113_i41
#ISCELL
  standard tap *
  page113_i42
#ISCELL
  standard tap *
  page113_i43
#ISCELL
  standard tap *
  page113_i44
#ISCELL
  standard tap *
  page113_i45
#ISCELL
  standard tap *
  page113_i46
#ISCELL
  standard tap *
  page113_i47
#ISCELL
  standard tap *
  page113_i48
#ISCELL
  standard tap *
  page113_i49
#ISCELL
  standard offpage *
  page113_i5
#ISCELL
  standard tap *
  page113_i50
#ISCELL
  standard tap *
  page113_i51
#ISCELL
  standard tap *
  page113_i52
#ISCELL
  standard tap *
  page113_i53
#ISCELL
  standard tap *
  page113_i54
#ISCELL
  standard tap *
  page113_i55
#ISCELL
  standard tap *
  page113_i56
#ISCELL
  standard tap *
  page113_i57
#ISCELL
  standard tap *
  page113_i58
#ISCELL
  standard tap *
  page113_i59
#ISCELL
  standard offpage *
  page113_i6
#ISCELL
  standard tap *
  page113_i60
#ISCELL
  standard tap *
  page113_i61
#ISCELL
  standard tap *
  page113_i62
#ISCELL
  standard tap *
  page113_i63
#ISCELL
  standard tap *
  page113_i64
#ISCELL
  standard tap *
  page113_i65
#ISCELL
  standard tap *
  page113_i66
#ISCELL
  standard tap *
  page113_i67
#ISCELL
  standard tap *
  page113_i68
#ISCELL
  standard tap *
  page113_i69
#ISCELL
  standard offpage *
  page113_i7
#ISCELL
  standard tap *
  page113_i70
#ISCELL
  standard tap *
  page113_i71
#ISCELL
  standard tap *
  page113_i72
#ISCELL
  standard tap *
  page113_i73
#ISCELL
  standard tap *
  page113_i74
#ISCELL
  standard tap *
  page113_i75
#ISCELL
  standard tap *
  page113_i76
#ISCELL
  standard tap *
  page113_i77
#ISCELL
  standard tap *
  page113_i78
#ISCELL
  standard tap *
  page113_i79
#ISCELL
  standard offpage *
  page113_i8
#ISCELL
  standard tap *
  page113_i80
#ISCELL
  standard tap *
  page113_i81
#ISCELL
  standard tap *
  page113_i82
#ISCELL
  standard tap *
  page113_i83
#ISCELL
  standard tap *
  page113_i84
#ISCELL
  standard tap *
  page113_i85
#ISCELL
  standard tap *
  page113_i86
#ISCELL
  standard tap *
  page113_i87
#ISCELL
  standard tap *
  page113_i88
#ISCELL
  standard tap *
  page113_i89
#ISCELL
  standard offpage *
  page113_i9
#ISCELL
  standard tap *
  page113_i90
#ISCELL
  standard tap *
  page113_i91
#ISCELL
  standard tap *
  page113_i92
#ISCELL
  standard tap *
  page113_i93
#ISCELL
  standard tap *
  page113_i94
#ISCELL
  standard tap *
  page113_i95
#ISCELL
  standard tap *
  page113_i96
#ISCELL
  standard tap *
  page113_i97
#ISCELL
  standard tap *
  page113_i98
#ISCELL
  standard tap *
  page113_i99
